(kicad_pcb
	(version 20241229)
	(generator "pcbnew")
	(generator_version "9.0")
	(general
		(thickness 1.6)
		(legacy_teardrops no)
	)
	(paper "A4")
	(title_block
		(title "GMSL Deserializer")
		(date "2025-10-09")
		(rev "1.0.4")
		(company "Antmicro Ltd")
		(comment 1 "www.antmicro.com")
		(comment 9 "footprints 21-25 of 235")
	)
	(layers
		(0 "F.Cu" signal)
		(4 "In1.Cu" power)
		(6 "In2.Cu" power)
		(2 "B.Cu" signal)
		(9 "F.Adhes" user "F.Adhesive")
		(11 "B.Adhes" user "B.Adhesive")
		(13 "F.Paste" user)
		(15 "B.Paste" user)
		(5 "F.SilkS" user "F.Silkscreen")
		(7 "B.SilkS" user "B.Silkscreen")
		(1 "F.Mask" user)
		(3 "B.Mask" user)
		(17 "Dwgs.User" user "User.Drawings")
		(19 "Cmts.User" user "User.Comments")
		(21 "Eco1.User" user "User.Eco1")
		(23 "Eco2.User" user "User.Eco2")
		(25 "Edge.Cuts" user)
		(27 "Margin" user)
		(31 "F.CrtYd" user "F.Courtyard")
		(29 "B.CrtYd" user "B.Courtyard")
		(35 "F.Fab" user)
		(33 "B.Fab" user)
	)
	(footprint "antmicro-footprints:SOT-23-5"
		(layer "F.Cu")
		(at 167.132 56.769 -90)
		(property "Reference" "U2"
			(at 2.159 1.778 270)
			(layer "F.SilkS")
			(effects
				(font
					(size 0.7 0.7)
					(thickness 0.15)
				)
				(justify left bottom)
			)
		)
		(property "Value" "SN74LV1T125DBVR"
			(at 0.002 2.799 90)
			(layer "F.Fab")
			(effects
				(font
					(size 0.7 0.7)
					(thickness 0.15)
				)
				(justify right bottom)
			)
		)
		(property "Datasheet" "https://www.ti.com/lit/ds/symlink/sn74lv1t125.pdf?HQS=dis-mous-null-mousermode-dsf-pf-null-wwe&ts=1627648952184&ref_url=https%253A%252F%252Fmouser.com%252F"
			(at 0 0 270)
			(layer "F.Fab")
			(hide yes)
			(effects
				(font
					(size 1.27 1.27)
					(thickness 0.15)
				)
			)
		)
		(property "Description" "Buffer, 74LV1T125, 1.6 V to 5.5 V, SOT-23-5"
			(at 0 0 270)
			(layer "F.Fab")
			(hide yes)
			(effects
				(font
					(size 1.27 1.27)
					(thickness 0.15)
				)
			)
		)
		(property "Author" "Antmicro"
			(at 110.363 223.901 0)
			(layer "F.Fab")
			(hide yes)
			(effects
				(font
					(size 1 1)
					(thickness 0.15)
				)
			)
		)
		(property "License" "Apache-2.0"
			(at 110.363 223.901 0)
			(layer "F.Fab")
			(hide yes)
			(effects
				(font
					(size 1 1)
					(thickness 0.15)
				)
			)
		)
		(property "MPN" "SN74LV1T125DBVR"
			(at 110.363 223.901 0)
			(layer "F.Fab")
			(hide yes)
			(effects
				(font
					(size 1 1)
					(thickness 0.15)
				)
			)
		)
		(property "Manufacturer" "Texas Instruments"
			(at 110.363 223.901 0)
			(layer "F.Fab")
			(hide yes)
			(effects
				(font
					(size 1 1)
					(thickness 0.15)
				)
			)
		)
		(sheetname "/Connectors/")
		(sheetfile "connectors.kicad_sch")
		(attr smd)
		(fp_line
			(start -0.85 1.6)
			(end -0.85 1.301)
			(stroke
				(width 0.15)
				(type solid)
			)
			(layer "F.SilkS")
		)
		(fp_line
			(start -0.55 1.6)
			(end -0.85 1.6)
			(stroke
				(width 0.15)
				(type solid)
			)
			(layer "F.SilkS")
		)
		(fp_line
			(start 0.8 1.599)
			(end 0.549 1.599)
			(stroke
				(width 0.15)
				(type solid)
			)
			(layer "F.SilkS")
		)
		(fp_line
			(start 0.8 1.3)
			(end 0.8 1.599)
			(stroke
				(width 0.15)
				(type solid)
			)
			(layer "F.SilkS")
		)
		(fp_line
			(start 0.8 0.55)
			(end 0.8 -0.55)
			(stroke
				(width 0.15)
				(type solid)
			)
			(layer "F.SilkS")
		)
		(fp_line
			(start 0.8 -1.3)
			(end 0.8 -1.6)
			(stroke
				(width 0.15)
				(type solid)
			)
			(layer "F.SilkS")
		)
		(fp_line
			(start -0.8 -1.6)
			(end -0.8 -1.3)
			(stroke
				(width 0.15)
				(type solid)
			)
			(layer "F.SilkS")
		)
		(fp_line
			(start -0.8 -1.6)
			(end -0.5 -1.6)
			(stroke
				(width 0.15)
				(type solid)
			)
			(layer "F.SilkS")
		)
		(fp_line
			(start 0.8 -1.6)
			(end 0.5 -1.6)
			(stroke
				(width 0.15)
				(type solid)
			)
			(layer "F.SilkS")
		)
		(fp_circle
			(center -1.25 -1.5)
			(end -1.2 -1.5)
			(stroke
				(width 0.15)
				(type solid)
			)
			(fill yes)
			(layer "F.SilkS")
		)
		(fp_rect
			(start 1.9 -1.76)
			(end -1.9 1.75)
			(stroke
				(width 0.05)
				(type solid)
			)
			(fill no)
			(layer "F.CrtYd")
		)
		(fp_line
			(start -0.398 -1.526)
			(end -0.874 -1.05)
			(stroke
				(width 0.15)
				(type solid)
			)
			(layer "F.Fab")
		)
		(fp_rect
			(start 0.874 1.523)
			(end -0.873 -1.525)
			(stroke
				(width 0.15)
				(type solid)
			)
			(fill no)
			(layer "F.Fab")
		)
		(pad "1" smd rect
			(at -1.351 -0.951 180)
			(size 0.55 1)
			(layers "F.Cu" "F.Mask" "F.Paste")
			(net 131 "Net-(U2-~{OE})")
			(pinfunction "~{OE}")
			(pintype "input")
		)
		(pad "2" smd rect
			(at -1.351 0 180)
			(size 0.55 1)
			(layers "F.Cu" "F.Mask" "F.Paste")
			(net 66 "/Connectors/VSYNC_CAM1")
			(pinfunction "A")
			(pintype "input")
		)
		(pad "3" smd rect
			(at -1.351 0.949 180)
			(size 0.55 1)
			(layers "F.Cu" "F.Mask" "F.Paste")
			(net 1 "GND")
			(pinfunction "GND")
			(pintype "power_in")
		)
		(pad "4" smd rect
			(at 1.35 0.949 180)
			(size 0.55 1)
			(layers "F.Cu" "F.Mask" "F.Paste")
			(net 132 "Net-(U2-Y)")
			(pinfunction "Y")
			(pintype "output")
		)
		(pad "5" smd rect
			(at 1.35 -0.951 180)
			(size 0.55 1)
			(layers "F.Cu" "F.Mask" "F.Paste")
			(net 3 "+1V8")
			(pinfunction "VCC")
			(pintype "power_in")
		)
	)
	(footprint "antmicro-footprints:L_Coilcraft-PFL1609"
		(layer "F.Cu")
		(at 128.524 53.594)
		(property "Reference" "L13"
			(at -1.498634 1.480804 0)
			(layer "F.SilkS")
			(effects
				(font
					(size 0.7 0.7)
					(thickness 0.15)
				)
				(justify left bottom)
			)
		)
		(property "Value" "L_470n_1A_Coilcraft-PFL1609"
			(at 0 2 0)
			(layer "F.Fab")
			(effects
				(font
					(size 0.7 0.7)
					(thickness 0.15)
				)
				(justify left bottom)
			)
		)
		(property "Datasheet" "https://www.coilcraft.com/getmedia/2f4cd442-d64d-4413-a518-12fcfd03318d/pfl1609.pdf"
			(at 0 0 0)
			(layer "F.Fab")
			(hide yes)
			(effects
				(font
					(size 1.27 1.27)
					(thickness 0.15)
				)
			)
		)
		(property "Description" "Power Inductor (SMT), 6.8 µH, 9.2 A, Shielded, 12.8 A, XAL7070"
			(at 0 0 0)
			(layer "F.Fab")
			(hide yes)
			(effects
				(font
					(size 1.27 1.27)
					(thickness 0.15)
				)
			)
		)
		(property "Author" "Antmicro"
			(at 0 0 0)
			(layer "F.Fab")
			(hide yes)
			(effects
				(font
					(size 1 1)
					(thickness 0.15)
				)
			)
		)
		(property "IMax" "1 A"
			(at 0 0 0)
			(layer "F.Fab")
			(hide yes)
			(effects
				(font
					(size 1 1)
					(thickness 0.15)
				)
			)
		)
		(property "ISat" "0.99 A"
			(at 0 0 0)
			(layer "F.Fab")
			(hide yes)
			(effects
				(font
					(size 1 1)
					(thickness 0.15)
				)
			)
		)
		(property "License" "Apache-2.0"
			(at 0 0 0)
			(layer "F.Fab")
			(hide yes)
			(effects
				(font
					(size 1 1)
					(thickness 0.15)
				)
			)
		)
		(property "MPN" "PFL1609-471"
			(at 0 0 0)
			(layer "F.Fab")
			(hide yes)
			(effects
				(font
					(size 1 1)
					(thickness 0.15)
				)
			)
		)
		(property "Manufacturer" "Coilcraft"
			(at 0 0 0)
			(layer "F.Fab")
			(hide yes)
			(effects
				(font
					(size 1 1)
					(thickness 0.15)
				)
			)
		)
		(property "Size" "1.07x1.8"
			(at 0 0 0)
			(layer "F.Fab")
			(hide yes)
			(effects
				(font
					(size 1 1)
					(thickness 0.15)
				)
			)
		)
		(property "Val" "470n/0.99A"
			(at 0 0 0)
			(layer "F.Fab")
			(hide yes)
			(effects
				(font
					(size 1 1)
					(thickness 0.15)
				)
			)
		)
		(sheetname "/Power/")
		(sheetfile "power.kicad_sch")
		(attr smd)
		(fp_line
			(start -0.23 -0.45)
			(end 0.23 -0.45)
			(stroke
				(width 0.15)
				(type solid)
			)
			(layer "F.SilkS")
		)
		(fp_line
			(start -0.23 0.45)
			(end 0.23 0.45)
			(stroke
				(width 0.15)
				(type solid)
			)
			(layer "F.SilkS")
		)
		(fp_rect
			(start -1.2 -0.84)
			(end 1.2 0.84)
			(stroke
				(width 0.05)
				(type solid)
			)
			(fill no)
			(layer "F.CrtYd")
		)
		(fp_rect
			(start -0.9 -0.535)
			(end 0.9 0.535)
			(stroke
				(width 0.15)
				(type solid)
			)
			(fill no)
			(layer "F.Fab")
		)
		(pad "1" smd roundrect
			(at -0.635 0)
			(size 0.64 1.02)
			(layers "F.Cu" "F.Mask" "F.Paste")
			(roundrect_rratio 0.15)
			(net 59 "Net-(L13-Pad1)")
			(pintype "passive")
		)
		(pad "2" smd roundrect
			(at 0.635 0)
			(size 0.64 1.02)
			(layers "F.Cu" "F.Mask" "F.Paste")
			(roundrect_rratio 0.15)
			(net 114 "/Connectors/PoCA")
			(pintype "passive")
		)
	)
	(footprint "antmicro-footprints:L_Coilcraft-MSS6132T"
		(layer "F.Cu")
		(at 135.128 61.976 90)
		(property "Reference" "L2"
			(at -0.635 -3.429 90)
			(layer "F.SilkS")
			(effects
				(font
					(size 0.7 0.7)
					(thickness 0.15)
				)
				(justify left bottom)
			)
		)
		(property "Value" "L_22u_1.12A_Coilcraft-MSS6132T"
			(at -0.508 4.826 90)
			(layer "F.Fab")
			(effects
				(font
					(size 0.7 0.7)
					(thickness 0.15)
				)
				(justify left bottom)
			)
		)
		(property "Datasheet" "https://www.coilcraft.com/getmedia/d035c9b3-191d-46aa-ab3f-5c1a849157c1/mss6132t.pdf"
			(at 0 0 90)
			(layer "F.Fab")
			(hide yes)
			(effects
				(font
					(size 1.27 1.27)
					(thickness 0.15)
				)
			)
		)
		(property "Description" "Power Inductor (SMT), 22 µH, 1.85 A, Shielded, 2.45 A, WE-MAPI"
			(at 0 0 90)
			(layer "F.Fab")
			(hide yes)
			(effects
				(font
					(size 1.27 1.27)
					(thickness 0.15)
				)
			)
		)
		(property "Author" "Antmicro"
			(at 197.104 -73.152 0)
			(layer "F.Fab")
			(hide yes)
			(effects
				(font
					(size 1 1)
					(thickness 0.15)
				)
			)
		)
		(property "IMax" "1.45A"
			(at 197.104 -73.152 0)
			(layer "F.Fab")
			(hide yes)
			(effects
				(font
					(size 1 1)
					(thickness 0.15)
				)
			)
		)
		(property "ISat" "1.12A"
			(at 197.104 -73.152 0)
			(layer "F.Fab")
			(hide yes)
			(effects
				(font
					(size 1 1)
					(thickness 0.15)
				)
			)
		)
		(property "License" "Apache-2.0"
			(at 197.104 -73.152 0)
			(layer "F.Fab")
			(hide yes)
			(effects
				(font
					(size 1 1)
					(thickness 0.15)
				)
			)
		)
		(property "MPN" "MSS6132T-223"
			(at 197.104 -73.152 0)
			(layer "F.Fab")
			(hide yes)
			(effects
				(font
					(size 1 1)
					(thickness 0.15)
				)
			)
		)
		(property "Manufacturer" "Coilcraft"
			(at 197.104 -73.152 0)
			(layer "F.Fab")
			(hide yes)
			(effects
				(font
					(size 1 1)
					(thickness 0.15)
				)
			)
		)
		(property "Size" "6.1x6.1"
			(at 197.104 -73.152 0)
			(layer "F.Fab")
			(hide yes)
			(effects
				(font
					(size 1 1)
					(thickness 0.15)
				)
			)
		)
		(property "Val" "22u/1.12A"
			(at 197.104 -73.152 0)
			(layer "F.Fab")
			(hide yes)
			(effects
				(font
					(size 1 1)
					(thickness 0.15)
				)
			)
		)
		(sheetname "/Power/")
		(sheetfile "power.kicad_sch")
		(attr smd)
		(fp_line
			(start -0.8 -3.05)
			(end 0.8 -3.05)
			(stroke
				(width 0.15)
				(type solid)
			)
			(layer "F.SilkS")
		)
		(fp_line
			(start -0.8 3.05)
			(end 0.8 3.05)
			(stroke
				(width 0.15)
				(type solid)
			)
			(layer "F.SilkS")
		)
		(fp_rect
			(start -3.35 -3.35)
			(end 3.35 3.35)
			(stroke
				(width 0.05)
				(type solid)
			)
			(fill no)
			(layer "F.CrtYd")
		)
		(fp_rect
			(start -3.1 -3.1)
			(end 3.1 3.1)
			(stroke
				(width 0.15)
				(type solid)
			)
			(fill no)
			(layer "F.Fab")
		)
		(pad "1" smd custom
			(at -2.71 0 180)
			(size 6 0.575)
			(layers "F.Cu" "F.Mask" "F.Paste")
			(net 4 "+12V")
			(pintype "passive")
			(options
				(clearance outline)
				(anchor rect)
			)
			(primitives
				(gr_poly
					(pts
						(xy 2.4 1.71) (xy 2.117646 1.21) (xy 1.9 0.96) (xy 1.65 0.71) (xy 1.2 0.41) (xy 0.4 0.11) (xy 0.4 0.01)
						(xy 2.9 0) (xy 2.9 1.71)
					)
					(width 0.2)
					(fill yes)
				)
				(gr_poly
					(pts
						(xy -2.4 1.731128) (xy -2.117646 1.231128) (xy -1.9 0.981128) (xy -1.65 0.731128) (xy -1.2 0.431128)
						(xy -0.4 0.131128) (xy -0.4 0.031128) (xy -2.9 0.021128) (xy -2.9 1.731128)
					)
					(width 0.2)
					(fill yes)
				)
			)
		)
		(pad "2" smd custom
			(at 2.71 0)
			(size 6 0.575)
			(layers "F.Cu" "F.Mask" "F.Paste")
			(net 52 "Net-(L2-Pad2)")
			(pintype "passive")
			(options
				(clearance outline)
				(anchor rect)
			)
			(primitives
				(gr_poly
					(pts
						(xy -2.4 1.731128) (xy -2.117646 1.231128) (xy -1.9 0.981128) (xy -1.65 0.731128) (xy -1.2 0.431128)
						(xy -0.4 0.131128) (xy -0.4 0.031128) (xy -2.9 0.021128) (xy -2.9 1.731128)
					)
					(width 0.2)
					(fill yes)
				)
				(gr_poly
					(pts
						(xy 2.4 1.71) (xy 2.117646 1.21) (xy 1.9 0.96) (xy 1.65 0.71) (xy 1.2 0.41) (xy 0.4 0.11) (xy 0.4 0.01)
						(xy 2.9 0) (xy 2.9 1.71)
					)
					(width 0.2)
					(fill yes)
				)
			)
		)
	)
	(footprint "antmicro-footprints:Conn_FAKRA_7-2287906-0"
		(layer "F.Cu")
		(at 163.782 38.348)
		(descr "Connector FAKRA, 5 pins")
		(property "Reference" "J5"
			(at 5.054 5.3 0)
			(layer "F.SilkS")
			(effects
				(font
					(size 0.7 0.7)
					(thickness 0.15)
				)
				(justify left bottom)
			)
		)
		(property "Value" "Conn_FAKRA_59S2AQ-40MT5-Z_1"
			(at -6.55 15.019 0)
			(layer "F.Fab")
			(effects
				(font
					(size 0.7 0.7)
					(thickness 0.15)
				)
				(justify left bottom)
			)
		)
		(property ki_fp_filters "*BNC* *SMA* *SMB* *SMC* *Cinch*")
		(sheetname "/Connectors/")
		(sheetfile "connectors.kicad_sch")
		(attr through_hole)
		(fp_line
			(start -4.572 0.94)
			(end -4.572 13.919)
			(stroke
				(width 0.15)
				(type solid)
			)
			(layer "F.SilkS")
		)
		(fp_line
			(start -4.572 13.919)
			(end 4.572 13.919)
			(stroke
				(width 0.15)
				(type solid)
			)
			(layer "F.SilkS")
		)
		(fp_line
			(start 4.572 0.94)
			(end -4.572 0.94)
			(stroke
				(width 0.15)
				(type solid)
			)
			(layer "F.SilkS")
		)
		(fp_line
			(start 4.572 13.919)
			(end 4.572 0.94)
			(stroke
				(width 0.15)
				(type solid)
			)
			(layer "F.SilkS")
		)
		(fp_rect
			(start -5.14 -12.64)
			(end 5.131 14.164)
			(stroke
				(width 0.05)
				(type solid)
			)
			(fill no)
			(layer "F.CrtYd")
		)
		(fp_text user "License: Apache-2.0"
			(at -6.55 16.219 0)
			(layer "F.Fab")
			(effects
				(font
					(size 0.7 0.7)
					(thickness 0.15)
				)
				(justify left bottom)
			)
		)
		(fp_text user "${REFERENCE}"
			(at -6.55 18.619 0)
			(layer "F.Fab")
			(effects
				(font
					(size 0.7 0.7)
					(thickness 0.15)
				)
				(justify left bottom)
			)
		)
		(fp_text user "Author: Antmicro"
			(at -6.55 17.419 0)
			(layer "F.Fab")
			(effects
				(font
					(size 0.7 0.7)
					(thickness 0.15)
				)
				(justify left bottom)
			)
		)
		(pad "1" smd roundrect
			(at 0 3.62 270)
			(size 4.79 1.9)
			(layers "F.Cu" "F.Mask" "F.Paste")
			(roundrect_rratio 0.25)
			(net 117 "/Connectors/PoCD")
			(pinfunction "1")
			(pintype "passive")
		)
		(pad "2" thru_hole circle
			(at -3 3.315 270)
			(size 1.8 1.8)
			(drill 1.45)
			(layers "*.Cu" "*.Mask")
			(remove_unused_layers no)
			(net 1 "GND")
			(pinfunction "2")
			(pintype "passive")
		)
		(pad "2" smd roundrect
			(at -2.9975 3.7175 270)
			(size 4.985 1.8)
			(layers "F.Cu" "F.Mask" "F.Paste")
			(roundrect_rratio 0.25)
			(net 1 "GND")
			(pinfunction "2")
			(pintype "passive")
		)
		(pad "3" thru_hole circle
			(at -3 10.315 270)
			(size 1.8 1.8)
			(drill 1.45)
			(layers "*.Cu" "*.Mask")
			(remove_unused_layers no)
			(net 1 "GND")
			(pinfunction "3")
			(pintype "passive")
		)
		(pad "3" smd roundrect
			(at -3 10.815 270)
			(size 5.6 1.8)
			(layers "F.Cu" "F.Mask" "F.Paste")
			(roundrect_rratio 0.25)
			(net 1 "GND")
			(pinfunction "3")
			(pintype "passive")
		)
		(pad "4" thru_hole circle
			(at 3 10.315 270)
			(size 1.8 1.8)
			(drill 1.45)
			(layers "*.Cu" "*.Mask")
			(remove_unused_layers no)
			(net 1 "GND")
			(pinfunction "4")
			(pintype "passive")
		)
		(pad "4" smd roundrect
			(at 3 10.815 270)
			(size 5.6 1.8)
			(layers "F.Cu" "F.Mask" "F.Paste")
			(roundrect_rratio 0.25)
			(net 1 "GND")
			(pinfunction "4")
			(pintype "passive")
		)
		(pad "5" thru_hole circle
			(at 3 3.315 270)
			(size 1.8 1.8)
			(drill 1.45)
			(layers "*.Cu" "*.Mask")
			(remove_unused_layers no)
			(net 1 "GND")
			(pinfunction "5")
			(pintype "passive")
		)
		(pad "5" smd roundrect
			(at 3 3.72 270)
			(size 4.99 1.8)
			(layers "F.Cu" "F.Mask" "F.Paste")
			(roundrect_rratio 0.25)
			(net 1 "GND")
			(pinfunction "5")
			(pintype "passive")
		)
	)
	(footprint "antmicro-footprints:R_0402_1005Metric"
		(layer "F.Cu")
		(at 172.132 64.87 90)
		(descr "Resistor SMD 0402")
		(tags "resistor SMD 0402")
		(property "Reference" "R59"
			(at -2.948 0.334 270)
			(layer "F.SilkS")
			(effects
				(font
					(size 0.7 0.7)
					(thickness 0.15)
				)
				(justify left bottom)
			)
		)
		(property "Value" "R_2k2_0402"
			(at -1.011843 1.772047 90)
			(layer "F.Fab")
			(effects
				(font
					(size 0.7 0.7)
					(thickness 0.15)
				)
				(justify left bottom)
			)
		)
		(property "Datasheet" "https://www.bourns.com/docs/product-datasheets/cr.pdf"
			(at 0 0 90)
			(layer "F.Fab")
			(hide yes)
			(effects
				(font
					(size 1.27 1.27)
					(thickness 0.15)
				)
			)
		)
		(property "Description" "SMD Chip Resistor, 2.2 kohm, ± 1%, 62.5 mW, 0402 [1005 Metric], Thick Film, General Purpose"
			(at 0 0 90)
			(layer "F.Fab")
			(hide yes)
			(effects
				(font
					(size 1.27 1.27)
					(thickness 0.15)
				)
			)
		)
		(property "Author" "Antmicro"
			(at 237.002 -107.262 0)
			(layer "F.Fab")
			(hide yes)
			(effects
				(font
					(size 1 1)
					(thickness 0.15)
				)
			)
		)
		(property "License" "Apache-2.0"
			(at 237.002 -107.262 0)
			(layer "F.Fab")
			(hide yes)
			(effects
				(font
					(size 1 1)
					(thickness 0.15)
				)
			)
		)
		(property "MPN" "CR0402-FX-2201GLF"
			(at 237.002 -107.262 0)
			(layer "F.Fab")
			(hide yes)
			(effects
				(font
					(size 1 1)
					(thickness 0.15)
				)
			)
		)
		(property "Manufacturer" "Bourns"
			(at 237.002 -107.262 0)
			(layer "F.Fab")
			(hide yes)
			(effects
				(font
					(size 1 1)
					(thickness 0.15)
				)
			)
		)
		(property "Tolerance" "1%"
			(at 237.002 -107.262 0)
			(layer "F.Fab")
			(hide yes)
			(effects
				(font
					(size 1 1)
					(thickness 0.15)
				)
			)
		)
		(property "Val" "2k2"
			(at 237.002 -107.262 0)
			(layer "F.Fab")
			(hide yes)
			(effects
				(font
					(size 1 1)
					(thickness 0.15)
				)
			)
		)
		(sheetname "/Connectors/")
		(sheetfile "connectors.kicad_sch")
		(attr smd)
		(fp_rect
			(start -0.925 -0.47)
			(end 0.925 0.47)
			(stroke
				(width 0.05)
				(type default)
			)
			(fill no)
			(layer "F.CrtYd")
		)
		(fp_rect
			(start -0.5 -0.25)
			(end 0.5 0.25)
			(stroke
				(width 0.15)
				(type solid)
			)
			(fill no)
			(layer "F.Fab")
		)
		(pad "1" smd roundrect
			(at -0.48 0 90)
			(size 0.59 0.64)
			(layers "F.Cu" "F.Mask" "F.Paste")
			(roundrect_rratio 0.25)
			(net 134 "Net-(U8-A_{2})")
			(pintype "passive")
		)
		(pad "2" smd roundrect
			(at 0.48 0 90)
			(size 0.59 0.64)
			(layers "F.Cu" "F.Mask" "F.Paste")
			(roundrect_rratio 0.25)
			(net 3 "+1V8")
			(pintype "passive")
		)
	)
)
